FILE_TYPE = CONNECTIVITY;
{Allegro Design Entry HDL 17.4-2019 S026 (4007227) 1/17/2022}
"PAGE_NUMBER" = 453;
0"NC";
1"GND\g";
2"GND\g";
3"GND\g";
4"GND\g";
5"SMB_RT_CPU1_P2_ROM_R_SCL";
6"SMB_RT_CPU1_P2_ROM_SCL";
7"SMB_RT_CPU1_P2_ROM_R_SDA";
8"SMB_RT_CPU1_P2_ROM_SDA";
9"U20_E2";
10"P1V8_CPU1_RT_1D\g";
%"UNIVERSAL_GND"
"1","(-4050,5350)","0","pure_quanta_power","I18";
;
CDS_LIB"pure_quanta_power"
HDL_POWER"GND";
"A"1;
%"Q_RES"
"2","(-3900,5425)","0","pure_quanta","I19";
;
LOCATION"R6790"
$SEC"1"
CDS_SEC"1"
WATTAGE"1/20W"
TOLERANCE"1%"
VALUE"1K"
MATERIAL"CHIP"
PACK_TYPE"0201LF"
CDS_LIB"pure_quanta"
PART_NUMBER"CS21001FE07";
"A"
$PN"1"9;
"B"
$PN"2"2;
%"UNIVERSAL_GND"
"1","(-3900,5075)","0","pure_quanta_power","I20";
;
CDS_LIB"pure_quanta_power"
HDL_POWER"GND";
"A"2;
%"UNIVERSAL_GND"
"1","(-5325,5625)","7","pure_quanta_power","I21";
;
CDS_LIB"pure_quanta_power"
HDL_POWER"GND";
"A"3;
%"P1V0"
"1","(-5300,6350)","0","pure_quanta_power","I22";
;
HDL_POWER"P1V8_CPU1_RT_1D"
CDS_LIB"pure_quanta_power";
"A"10;
%"Q_CAP"
"1","(-5600,6025)","0","pure_quanta","I23";
;
LOCATION"C7503"
$SEC"1"
CDS_SEC"1"
MATERIAL"X7S"
PACK_TYPE"C0201"
VALUE"0.1UF"
TOLERANCE"10%"
VOLTAGE"10V"
CDS_LIB"pure_quanta"
PART_NUMBER"CH4102K6E00";
"B"
$PN"2"4;
"A"
$PN"1"10;
%"UNIVERSAL_GND"
"1","(-5600,5825)","0","pure_quanta_power","I24";
;
CDS_LIB"pure_quanta_power"
HDL_POWER"GND";
"A"4;
%"Q_RES"
"1","(-6300,5525)","0","pure_quanta","I3";
;
LOCATION"R694"
$SEC"1"
CDS_SEC"1"
MATERIAL"CHIP"
CDS_LIB"pure_quanta"
WATTAGE"1/20W"
PACK_TYPE"0201LF"
VALUE"33.2"
TOLERANCE"1%"
PART_NUMBER"CS03321FE09";
"B"
$PN"2"8;
"A"
$PN"1"7;
%"Q_RES"
"1","(-6300,5575)","0","pure_quanta","I4";
;
LOCATION"R693"
$SEC"1"
CDS_SEC"1"
MATERIAL"CHIP"
WATTAGE"1/20W"
PACK_TYPE"0201LF"
VALUE"33.2"
TOLERANCE"1%"
CDS_LIB"pure_quanta"
PART_NUMBER"CS03321FE09";
"B"
$PN"2"6;
"A"
$PN"1"5;
%"M24M02DRMN6TP"
"1","(-4875,5600)","0","pure_quanta","I5";
;
LOCATION"U20"
$SEC"1"
CDS_SEC"1"
MATERIAL"IC"
PART_TYPE"SMLF"
VALUE"M24M02-DRMN6TP"
NEEDS_NO_SIZE"TRUE"
CDS_LMAN_SYM_OUTLINE"-175,125,175,-125"
CDS_LIB"pure_quanta"
PART_NUMBER"AKE33Z00600";
"DU1"
$PN"1"0;
"DU2"
$PN"2"0;
"E2"
$PN"3"9;
"VSS"
$PN"4"1;
"SDA"
$PN"5"8;
"SCL"
$PN"6"6;
"WC_N \B"
$PN"7"3;
"VCC"
$PN"8"10;
END.
